(kicad_pcb
	(version 20260206)
	(generator "pcbnew")
	(generator_version "10.0")
	(general
		(thickness 1.6)
		(legacy_teardrops no)
	)
	(paper "A4")
	(title_block
		(title "peb — Lightning_PEB_BRD.brd")
		(comment 1 "Lightning (Wiwynn / Facebook NVMe JBOF) / footprints 1344-1351 of 2563")
	)
	(layers
		(0 "F.Cu" signal "TOP")
		(4 "In1.Cu" signal "L2GND")
		(6 "In2.Cu" signal "L3")
		(8 "In3.Cu" signal "L4VCC")
		(10 "In4.Cu" signal "L5VCC")
		(12 "In5.Cu" signal "L6")
		(14 "In6.Cu" signal "L7GND")
		(2 "B.Cu" signal "BOTTOM")
		(9 "F.Adhes" user "F.Adhesive")
		(11 "B.Adhes" user "B.Adhesive")
		(13 "F.Paste" user "Package Geometry/Pastemask Top")
		(15 "B.Paste" user "Package Geometry/Pastemask Bottom")
		(5 "F.SilkS" user "Ref Des/Silkscreen Top")
		(7 "B.SilkS" user "Ref Des/Silkscreen Bottom")
		(1 "F.Mask" user "Board Geometry/Soldermask Top")
		(3 "B.Mask" user "Board Geometry/Soldermask Bottom")
		(17 "Dwgs.User" user "User.Drawings")
		(19 "Cmts.User" user "User.Comments")
		(21 "Eco1.User" user "User.Eco1")
		(23 "Eco2.User" user "User.Eco2")
		(25 "Edge.Cuts" user "Board Geometry/Outline")
		(27 "Margin" user)
		(31 "F.CrtYd" user "Package Geometry/Place Bound Top")
		(29 "B.CrtYd" user "Package Geometry/Place Bound Bottom")
		(35 "F.Fab" user "Ref Des/Assembly Top")
		(33 "B.Fab" user "Ref Des/Assembly Bottom")
	)
	(footprint ""
		(layer "F.Cu")
		(at 16.51 -194.2592)
		(property "Reference" "R2171"
			(at 0 0 0)
			(layer "F.SilkS")
			(hide yes)
			(effects
				(font
					(size 1.27 1.27)
				)
			)
		)
		(property "Value" "100KR2J-4-GP"
			(at 0.064008 -3.993896 0)
			(unlocked yes)
			(layer "F.Fab")
			(hide yes)
			(effects
				(font
					(size 1.016 1.016)
					(thickness 0.1524)
				)
			)
		)
		(property "Device Type" "R402H15"
			(at 0.064008 -5.517896 0)
			(unlocked yes)
			(layer "F.Fab")
			(hide yes)
			(effects
				(font
					(size 1.016 1.016)
					(thickness 0.1524)
				)
			)
		)
		(duplicate_pad_numbers_are_jumpers no)
		(fp_line
			(start -0.508 -0.9398)
			(end -0.508 0.9398)
			(stroke
				(width 0.1524)
				(type default)
			)
			(layer "F.SilkS")
		)
		(fp_line
			(start 0.508 -0.9398)
			(end -0.508 -0.9398)
			(stroke
				(width 0.1524)
				(type default)
			)
			(layer "F.SilkS")
		)
		(fp_rect
			(start -0.508 0.9398)
			(end 0.508 -0.9398)
			(stroke
				(width 0)
				(type default)
			)
			(fill no)
			(layer "F.CrtYd")
		)
		(fp_rect
			(start -0.508 0.9398)
			(end 0.508 -0.9398)
			(stroke
				(width 0)
				(type default)
			)
			(fill no)
			(layer "F.Fab")
		)
		(pad "1" smd custom
			(at 0 -0.4445)
			(size 0.1397 0.1397)
			(layers "F.Cu" "F.Mask" "F.Paste")
			(net "MB0_VCAP_R")
			(options
				(clearance outline)
				(anchor circle)
			)
			(primitives
				(gr_poly
					(pts
						(arc
							(start -0.1778 -0.2794)
							(mid -0.249642 -0.249642)
							(end -0.2794 -0.1778)
						)
						(arc
							(start -0.2794 0.1778)
							(mid -0.249642 0.249642)
							(end -0.1778 0.2794)
						)
						(arc
							(start 0.1778 0.2794)
							(mid 0.249642 0.249642)
							(end 0.2794 0.1778)
						)
						(arc
							(start 0.2794 -0.1778)
							(mid 0.249642 -0.249642)
							(end 0.1778 -0.2794)
						)
					)
					(width 0)
					(fill yes)
				)
			)
		)
		(pad "2" smd custom
			(at 0 0.4445)
			(size 0.1397 0.1397)
			(layers "F.Cu" "F.Mask" "F.Paste")
			(net "MB0_PSET_R")
			(options
				(clearance outline)
				(anchor circle)
			)
			(primitives
				(gr_poly
					(pts
						(arc
							(start -0.1778 -0.2794)
							(mid -0.249642 -0.249642)
							(end -0.2794 -0.1778)
						)
						(arc
							(start -0.2794 0.1778)
							(mid -0.249642 0.249642)
							(end -0.1778 0.2794)
						)
						(arc
							(start 0.1778 0.2794)
							(mid 0.249642 0.249642)
							(end 0.2794 0.1778)
						)
						(arc
							(start 0.2794 -0.1778)
							(mid 0.249642 -0.249642)
							(end 0.1778 -0.2794)
						)
					)
					(width 0)
					(fill yes)
				)
			)
		)
	)
	(footprint ""
		(layer "F.Cu")
		(at 19.939 -157.48 180)
		(property "Reference" "D1401"
			(at 0 0 180)
			(layer "F.SilkS")
			(hide yes)
			(effects
				(font
					(size 1.27 1.27)
				)
			)
		)
		(property "Value" "RB551V30-GP"
			(at 0 -6.7818 180)
			(unlocked yes)
			(layer "F.Fab")
			(hide yes)
			(effects
				(font
					(size 1.016 1.016)
					(thickness 0.1524)
				)
			)
		)
		(property "Device Type" "SOD323AKH38"
			(at 0 -8.6868 180)
			(unlocked yes)
			(layer "F.Fab")
			(hide yes)
			(effects
				(font
					(size 1.016 1.016)
					(thickness 0.1524)
				)
			)
		)
		(duplicate_pad_numbers_are_jumpers no)
		(fp_line
			(start 0.889 2.159)
			(end -0.889 2.159)
			(stroke
				(width 0.1524)
				(type default)
			)
			(layer "F.SilkS")
		)
		(fp_line
			(start 0.889 -1.9304)
			(end 0.889 2.159)
			(stroke
				(width 0.1524)
				(type default)
			)
			(layer "F.SilkS")
		)
		(fp_line
			(start 0.762 2.0574)
			(end -0.762 2.0574)
			(stroke
				(width 0.508)
				(type default)
			)
			(layer "F.SilkS")
		)
		(fp_line
			(start -0.889 2.159)
			(end -0.889 -1.9304)
			(stroke
				(width 0.1524)
				(type default)
			)
			(layer "F.SilkS")
		)
		(fp_line
			(start -0.889 -1.9304)
			(end 0.889 -1.9304)
			(stroke
				(width 0.1524)
				(type default)
			)
			(layer "F.SilkS")
		)
		(fp_rect
			(start -1.016 2.3114)
			(end 1.016 -2.0066)
			(stroke
				(width 0)
				(type default)
			)
			(fill no)
			(layer "F.CrtYd")
		)
		(fp_poly
			(pts
				(xy -1.016 -2.0066) (xy 1.016 -2.0066) (xy 1.016 2.3114) (xy -1.016 2.3114)
			)
			(stroke
				(width 0)
				(type default)
			)
			(fill no)
			(layer "F.Fab")
		)
		(pad "A" smd rect
			(at 0 -1.143 180)
			(size 0.5588 1.016)
			(layers "F.Cu" "F.Mask" "F.Paste")
			(net "HOST_I2C_RESET_N_D")
		)
		(pad "K" smd rect
			(at 0 1.143 180)
			(size 0.5588 1.016)
			(layers "F.Cu" "F.Mask" "F.Paste")
			(net "HOST_I2C_RESET_N")
		)
	)
	(footprint ""
		(layer "F.Cu")
		(at 57.404 -130.048 180)
		(property "Reference" "C193"
			(at 0 0 180)
			(layer "F.SilkS")
			(hide yes)
			(effects
				(font
					(size 1.27 1.27)
				)
			)
		)
		(property "Value" "SC100P50V2JN-3GP"
			(at 1.1811 -2.7051 180)
			(unlocked yes)
			(layer "F.Fab")
			(hide yes)
			(effects
				(font
					(size 1.016 1.016)
					(thickness 0.1524)
				)
			)
		)
		(property "Device Type" "C402H22"
			(at 1.1811 -4.2291 180)
			(unlocked yes)
			(layer "F.Fab")
			(hide yes)
			(effects
				(font
					(size 1.016 1.016)
					(thickness 0.1524)
				)
			)
		)
		(duplicate_pad_numbers_are_jumpers no)
		(fp_rect
			(start -0.4318 0.9525)
			(end 0.4318 -0.9525)
			(stroke
				(width 0)
				(type default)
			)
			(fill no)
			(layer "F.CrtYd")
		)
		(fp_rect
			(start -0.4318 0.9525)
			(end 0.4318 -0.9525)
			(stroke
				(width 0)
				(type default)
			)
			(fill no)
			(layer "F.Fab")
		)
		(pad "1" smd custom
			(at 0 -0.4445 180)
			(size 0.1524 0.1524)
			(layers "F.Cu" "F.Mask" "F.Paste")
			(net "ADCAV33")
			(options
				(clearance outline)
				(anchor circle)
			)
			(primitives
				(gr_poly
					(pts
						(arc
							(start 0.3048 -0.2032)
							(mid 0.275042 -0.275042)
							(end 0.2032 -0.3048)
						)
						(arc
							(start -0.2032 -0.3048)
							(mid -0.275042 -0.275042)
							(end -0.3048 -0.2032)
						)
						(arc
							(start -0.3048 0.2032)
							(mid -0.275042 0.275042)
							(end -0.2032 0.3048)
						)
						(arc
							(start 0.2032 0.3048)
							(mid 0.275042 0.275042)
							(end 0.3048 0.2032)
						)
					)
					(width 0)
					(fill yes)
				)
			)
		)
		(pad "2" smd custom
			(at 0 0.4445 180)
			(size 0.1524 0.1524)
			(layers "F.Cu" "F.Mask" "F.Paste")
			(net "GND")
			(options
				(clearance outline)
				(anchor circle)
			)
			(primitives
				(gr_poly
					(pts
						(arc
							(start 0.3048 -0.2032)
							(mid 0.275042 -0.275042)
							(end 0.2032 -0.3048)
						)
						(arc
							(start -0.2032 -0.3048)
							(mid -0.275042 -0.275042)
							(end -0.3048 -0.2032)
						)
						(arc
							(start -0.3048 0.2032)
							(mid -0.275042 0.275042)
							(end -0.2032 0.3048)
						)
						(arc
							(start 0.2032 0.3048)
							(mid 0.275042 0.275042)
							(end 0.3048 0.2032)
						)
					)
					(width 0)
					(fill yes)
				)
			)
		)
	)
	(footprint ""
		(layer "F.Cu")
		(at 59.182 -45.085 -90)
		(property "Reference" "PC24"
			(at 0 0 270)
			(layer "F.SilkS")
			(hide yes)
			(effects
				(font
					(size 1.27 1.27)
				)
			)
		)
		(property "Value" "SC10U25V5KX-GP"
			(at -0.0762 -6.1214 270)
			(unlocked yes)
			(layer "F.Fab")
			(hide yes)
			(effects
				(font
					(size 1.016 1.016)
					(thickness 0.1524)
				)
			)
		)
		(property "Device Type" "C805H56"
			(at -0.0762 -8.1534 270)
			(unlocked yes)
			(layer "F.Fab")
			(hide yes)
			(effects
				(font
					(size 1.016 1.016)
					(thickness 0.1524)
				)
			)
		)
		(duplicate_pad_numbers_are_jumpers no)
		(fp_line
			(start 0.635 0)
			(end -0.635 0)
			(stroke
				(width 0.508)
				(type default)
			)
			(layer "F.SilkS")
		)
		(fp_rect
			(start -0.9652 1.778)
			(end 0.9652 -1.778)
			(stroke
				(width 0)
				(type default)
			)
			(fill no)
			(layer "F.CrtYd")
		)
		(fp_poly
			(pts
				(xy -0.9652 -1.778) (xy 0.9652 -1.778) (xy 0.9652 1.778) (xy -0.9652 1.778)
			)
			(stroke
				(width 0)
				(type default)
			)
			(fill no)
			(layer "F.Fab")
		)
		(pad "1" smd rect
			(at 0 -0.9652 270)
			(size 1.397 1.143)
			(layers "F.Cu" "F.Mask" "F.Paste")
			(net "P3V3_STBY_VIN")
		)
		(pad "2" smd rect
			(at 0 0.9652 270)
			(size 1.397 1.143)
			(layers "F.Cu" "F.Mask" "F.Paste")
			(net "GND")
		)
	)
	(footprint ""
		(layer "F.Cu")
		(at 39.67099 -84.279994 90)
		(property "Reference" "Q45"
			(at 0 0 90)
			(layer "F.SilkS")
			(hide yes)
			(effects
				(font
					(size 1.27 1.27)
				)
			)
		)
		(property "Value" "2N7002K-1-GP"
			(at 0.127 -8.9662 90)
			(unlocked yes)
			(layer "F.Fab")
			(hide yes)
			(effects
				(font
					(size 1.016 1.016)
					(thickness 0.1524)
				)
			)
		)
		(property "Device Type" "SOT23DGS2D4H44"
			(at 0.127 -10.4902 90)
			(unlocked yes)
			(layer "F.Fab")
			(hide yes)
			(effects
				(font
					(size 1.016 1.016)
					(thickness 0.1524)
				)
			)
		)
		(duplicate_pad_numbers_are_jumpers no)
		(fp_line
			(start 1.651 -1.778)
			(end -1.651 -1.778)
			(stroke
				(width 0.1524)
				(type default)
			)
			(layer "F.SilkS")
		)
		(fp_line
			(start -1.651 -1.778)
			(end -1.651 1.778)
			(stroke
				(width 0.1524)
				(type default)
			)
			(layer "F.SilkS")
		)
		(fp_line
			(start 1.651 1.778)
			(end 1.651 -1.778)
			(stroke
				(width 0.1524)
				(type default)
			)
			(layer "F.SilkS")
		)
		(fp_line
			(start -1.651 1.778)
			(end 1.651 1.778)
			(stroke
				(width 0.1524)
				(type default)
			)
			(layer "F.SilkS")
		)
		(fp_poly
			(pts
				(xy -1.778 1.8796) (xy -1.778 -1.8796) (xy 1.778 -1.8796) (xy 1.778 1.8796)
			)
			(stroke
				(width 0)
				(type default)
			)
			(fill no)
			(layer "F.CrtYd")
		)
		(fp_poly
			(pts
				(xy -1.778 1.8796) (xy -1.778 -1.8796) (xy 1.778 -1.8796) (xy 1.778 1.8796)
			)
			(stroke
				(width 0)
				(type default)
			)
			(fill no)
			(layer "F.Fab")
		)
		(pad "D" smd custom
			(at 0 -0.9525 90)
			(size 0.1905 0.1905)
			(layers "F.Cu" "F.Mask" "F.Paste")
			(net "Q45_D")
			(options
				(clearance outline)
				(anchor circle)
			)
			(primitives
				(gr_poly
					(pts
						(arc
							(start -0.1778 0.5715)
							(mid -0.321484 0.511984)
							(end -0.381 0.3683)
						)
						(arc
							(start -0.381 -0.3683)
							(mid -0.321484 -0.511984)
							(end -0.1778 -0.5715)
						)
						(arc
							(start 0.1778 -0.5715)
							(mid 0.321484 -0.511984)
							(end 0.381 -0.3683)
						)
						(arc
							(start 0.381 0.3683)
							(mid 0.321484 0.511984)
							(end 0.1778 0.5715)
						)
					)
					(width 0)
					(fill yes)
				)
			)
		)
		(pad "G" smd custom
			(at -0.98425 0.9525 90)
			(size 0.1905 0.1905)
			(layers "F.Cu" "F.Mask" "F.Paste")
			(net "MB0_P12V_PWRGOOD")
			(options
				(clearance outline)
				(anchor circle)
			)
			(primitives
				(gr_poly
					(pts
						(arc
							(start -0.1778 0.5715)
							(mid -0.321484 0.511984)
							(end -0.381 0.3683)
						)
						(arc
							(start -0.381 -0.3683)
							(mid -0.321484 -0.511984)
							(end -0.1778 -0.5715)
						)
						(arc
							(start 0.1778 -0.5715)
							(mid 0.321484 -0.511984)
							(end 0.381 -0.3683)
						)
						(arc
							(start 0.381 0.3683)
							(mid 0.321484 0.511984)
							(end 0.1778 0.5715)
						)
					)
					(width 0)
					(fill yes)
				)
			)
		)
		(pad "S" smd custom
			(at 0.98425 0.9525 90)
			(size 0.1905 0.1905)
			(layers "F.Cu" "F.Mask" "F.Paste")
			(net "GND")
			(options
				(clearance outline)
				(anchor circle)
			)
			(primitives
				(gr_poly
					(pts
						(arc
							(start -0.1778 0.5715)
							(mid -0.321484 0.511984)
							(end -0.381 0.3683)
						)
						(arc
							(start -0.381 -0.3683)
							(mid -0.321484 -0.511984)
							(end -0.1778 -0.5715)
						)
						(arc
							(start 0.1778 -0.5715)
							(mid 0.321484 -0.511984)
							(end 0.381 -0.3683)
						)
						(arc
							(start 0.381 0.3683)
							(mid 0.321484 0.511984)
							(end 0.1778 0.5715)
						)
					)
					(width 0)
					(fill yes)
				)
			)
		)
	)
	(footprint ""
		(layer "F.Cu")
		(at 140.850874 -95.27032 -90)
		(property "Reference" "PC91"
			(at 0 0 270)
			(layer "F.SilkS")
			(hide yes)
			(effects
				(font
					(size 1.27 1.27)
				)
			)
		)
		(property "Value" "SC10U10V5KX-6-GP-U"
			(at -0.0762 -6.1214 270)
			(unlocked yes)
			(layer "F.Fab")
			(hide yes)
			(effects
				(font
					(size 1.016 1.016)
					(thickness 0.1524)
				)
			)
		)
		(property "Device Type" "C805H58"
			(at -0.0762 -8.1534 270)
			(unlocked yes)
			(layer "F.Fab")
			(hide yes)
			(effects
				(font
					(size 1.016 1.016)
					(thickness 0.1524)
				)
			)
		)
		(duplicate_pad_numbers_are_jumpers no)
		(fp_line
			(start 0.635 0)
			(end -0.635 0)
			(stroke
				(width 0.508)
				(type default)
			)
			(layer "F.SilkS")
		)
		(fp_rect
			(start -0.9652 1.778)
			(end 0.9652 -1.778)
			(stroke
				(width 0)
				(type default)
			)
			(fill no)
			(layer "F.CrtYd")
		)
		(fp_poly
			(pts
				(xy -0.9652 -1.778) (xy 0.9652 -1.778) (xy 0.9652 1.778) (xy -0.9652 1.778)
			)
			(stroke
				(width 0)
				(type default)
			)
			(fill no)
			(layer "F.Fab")
		)
		(pad "1" smd rect
			(at 0 -0.9652 270)
			(size 1.397 1.143)
			(layers "F.Cu" "F.Mask" "F.Paste")
			(net "VR_P1V8_STBY_BIAS")
		)
		(pad "2" smd rect
			(at 0 0.9652 270)
			(size 1.397 1.143)
			(layers "F.Cu" "F.Mask" "F.Paste")
			(net "GND")
		)
	)
	(footprint ""
		(layer "F.Cu")
		(at 158.608268 -212.420454 180)
		(property "Reference" "C169"
			(at 0 0 180)
			(layer "F.SilkS")
			(hide yes)
			(effects
				(font
					(size 1.27 1.27)
				)
			)
		)
		(property "Value" "SCD22U10V2KX-1GP"
			(at 1.1811 -2.7051 180)
			(unlocked yes)
			(layer "F.Fab")
			(hide yes)
			(effects
				(font
					(size 1.016 1.016)
					(thickness 0.1524)
				)
			)
		)
		(property "Device Type" "C402H22"
			(at 1.1811 -4.2291 180)
			(unlocked yes)
			(layer "F.Fab")
			(hide yes)
			(effects
				(font
					(size 1.016 1.016)
					(thickness 0.1524)
				)
			)
		)
		(duplicate_pad_numbers_are_jumpers no)
		(fp_rect
			(start -0.4318 0.9525)
			(end 0.4318 -0.9525)
			(stroke
				(width 0)
				(type default)
			)
			(fill no)
			(layer "F.CrtYd")
		)
		(fp_rect
			(start -0.4318 0.9525)
			(end 0.4318 -0.9525)
			(stroke
				(width 0)
				(type default)
			)
			(fill no)
			(layer "F.Fab")
		)
		(pad "1" smd custom
			(at 0 -0.4445 180)
			(size 0.1524 0.1524)
			(layers "F.Cu" "F.Mask" "F.Paste")
			(net "PCIE_TX_CAP_N53")
			(options
				(clearance outline)
				(anchor circle)
			)
			(primitives
				(gr_poly
					(pts
						(arc
							(start 0.3048 -0.2032)
							(mid 0.275042 -0.275042)
							(end 0.2032 -0.3048)
						)
						(arc
							(start -0.2032 -0.3048)
							(mid -0.275042 -0.275042)
							(end -0.3048 -0.2032)
						)
						(arc
							(start -0.3048 0.2032)
							(mid -0.275042 0.275042)
							(end -0.2032 0.3048)
						)
						(arc
							(start 0.2032 0.3048)
							(mid 0.275042 0.275042)
							(end 0.3048 0.2032)
						)
					)
					(width 0)
					(fill yes)
				)
			)
		)
		(pad "2" smd custom
			(at 0 0.4445 180)
			(size 0.1524 0.1524)
			(layers "F.Cu" "F.Mask" "F.Paste")
			(net "PCIE_TX_N53")
			(options
				(clearance outline)
				(anchor circle)
			)
			(primitives
				(gr_poly
					(pts
						(arc
							(start 0.3048 -0.2032)
							(mid 0.275042 -0.275042)
							(end 0.2032 -0.3048)
						)
						(arc
							(start -0.2032 -0.3048)
							(mid -0.275042 -0.275042)
							(end -0.3048 -0.2032)
						)
						(arc
							(start -0.3048 0.2032)
							(mid -0.275042 0.275042)
							(end -0.2032 0.3048)
						)
						(arc
							(start 0.2032 0.3048)
							(mid 0.275042 0.275042)
							(end 0.3048 0.2032)
						)
					)
					(width 0)
					(fill yes)
				)
			)
		)
	)
	(footprint ""
		(layer "F.Cu")
		(at 66.3448 -26.3144)
		(property "Reference" "R737"
			(at 0 0 0)
			(layer "F.SilkS")
			(hide yes)
			(effects
				(font
					(size 1.27 1.27)
				)
			)
		)
		(property "Value" "0R2J-2-GP"
			(at 0.064008 -3.993896 0)
			(unlocked yes)
			(layer "F.Fab")
			(hide yes)
			(effects
				(font
					(size 1.016 1.016)
					(thickness 0.1524)
				)
			)
		)
		(property "Device Type" "R402H16"
			(at 0.064008 -5.517896 0)
			(unlocked yes)
			(layer "F.Fab")
			(hide yes)
			(effects
				(font
					(size 1.016 1.016)
					(thickness 0.1524)
				)
			)
		)
		(duplicate_pad_numbers_are_jumpers no)
		(fp_line
			(start -0.508 -0.9398)
			(end -0.508 0.9398)
			(stroke
				(width 0.1524)
				(type default)
			)
			(layer "F.SilkS")
		)
		(fp_line
			(start 0.508 -0.9398)
			(end -0.508 -0.9398)
			(stroke
				(width 0.1524)
				(type default)
			)
			(layer "F.SilkS")
		)
		(fp_rect
			(start -0.508 0.9398)
			(end 0.508 -0.9398)
			(stroke
				(width 0)
				(type default)
			)
			(fill no)
			(layer "F.CrtYd")
		)
		(fp_rect
			(start -0.508 0.9398)
			(end 0.508 -0.9398)
			(stroke
				(width 0)
				(type default)
			)
			(fill no)
			(layer "F.Fab")
		)
		(pad "1" smd custom
			(at 0 -0.4445)
			(size 0.1397 0.1397)
			(layers "F.Cu" "F.Mask" "F.Paste")
			(net "BMC_I2C14_MINI8_SCL_S")
			(options
				(clearance outline)
				(anchor circle)
			)
			(primitives
				(gr_poly
					(pts
						(arc
							(start -0.1778 -0.2794)
							(mid -0.249642 -0.249642)
							(end -0.2794 -0.1778)
						)
						(arc
							(start -0.2794 0.1778)
							(mid -0.249642 0.249642)
							(end -0.1778 0.2794)
						)
						(arc
							(start 0.1778 0.2794)
							(mid 0.249642 0.249642)
							(end 0.2794 0.1778)
						)
						(arc
							(start 0.2794 -0.1778)
							(mid 0.249642 -0.249642)
							(end 0.1778 -0.2794)
						)
					)
					(width 0)
					(fill yes)
				)
			)
		)
		(pad "2" smd custom
			(at 0 0.4445)
			(size 0.1397 0.1397)
			(layers "F.Cu" "F.Mask" "F.Paste")
			(net "IPMB_CLK")
			(options
				(clearance outline)
				(anchor circle)
			)
			(primitives
				(gr_poly
					(pts
						(arc
							(start -0.1778 -0.2794)
							(mid -0.249642 -0.249642)
							(end -0.2794 -0.1778)
						)
						(arc
							(start -0.2794 0.1778)
							(mid -0.249642 0.249642)
							(end -0.1778 0.2794)
						)
						(arc
							(start 0.1778 0.2794)
							(mid 0.249642 0.249642)
							(end 0.2794 0.1778)
						)
						(arc
							(start 0.2794 -0.1778)
							(mid 0.249642 -0.249642)
							(end 0.1778 -0.2794)
						)
					)
					(width 0)
					(fill yes)
				)
			)
		)
	)
)
